(kicad_pcb
	(version 20260206)
	(generator "pcbnew")
	(generator_version "10.0")
	(general
		(thickness 1.6)
		(legacy_teardrops no)
	)
	(paper "A4")
	(title_block
		(title "03242023_DA0F0TMBIJ0_F0T_Motherboard_J_brd_V01_OCP.brd")
		(comment 1 "Grand Teton / footprints 5999-6003 of 6105")
	)
	(layers
		(0 "F.Cu" signal "TOP")
		(4 "In1.Cu" signal "GND")
		(6 "In2.Cu" signal "IN1")
		(8 "In3.Cu" signal "GND1")
		(10 "In4.Cu" signal "IN2")
		(12 "In5.Cu" signal "GND2")
		(14 "In6.Cu" signal "IN3")
		(16 "In7.Cu" signal "GND3")
		(18 "In8.Cu" signal "VCC")
		(20 "In9.Cu" signal "VCC1")
		(22 "In10.Cu" signal "GND4")
		(24 "In11.Cu" signal "IN4")
		(26 "In12.Cu" signal "GND5")
		(28 "In13.Cu" signal "IN5")
		(30 "In14.Cu" signal "GND6")
		(32 "In15.Cu" signal "IN6")
		(34 "In16.Cu" signal "GND7")
		(2 "B.Cu" signal "BOTTOM")
		(9 "F.Adhes" user "F.Adhesive")
		(11 "B.Adhes" user "B.Adhesive")
		(13 "F.Paste" user "Package Geometry/Pastemask Top")
		(15 "B.Paste" user "Package Geometry/Pastemask Bottom")
		(5 "F.SilkS" user "Ref Des/Silkscreen Top")
		(7 "B.SilkS" user "Ref Des/Silkscreen Bottom")
		(1 "F.Mask" user "Board Geometry/Soldermask Top")
		(3 "B.Mask" user "Board Geometry/Soldermask Bottom")
		(17 "Dwgs.User" user "User.Drawings")
		(19 "Cmts.User" user "User.Comments")
		(21 "Eco1.User" user "User.Eco1")
		(23 "Eco2.User" user "User.Eco2")
		(25 "Edge.Cuts" user "Board Geometry/Outline")
		(27 "Margin" user)
		(31 "F.CrtYd" user "Package Geometry/Place Bound Top")
		(29 "B.CrtYd" user "Package Geometry/Place Bound Bottom")
		(35 "F.Fab" user "Ref Des/Assembly Top")
		(33 "B.Fab" user "Ref Des/Assembly Bottom")
	)
	(footprint ""
		(layer "B.Cu")
		(at 63.55588 -8.981948 90)
		(property "Reference" "C1838"
			(at 0 0 90)
			(layer "B.SilkS")
			(hide yes)
			(effects
				(font
					(size 1.27 1.27)
				)
				(justify mirror)
			)
		)
		(property "Value" ""
			(at 0 0 90)
			(layer "B.Fab")
			(effects
				(font
					(size 1.27 1.27)
				)
				(justify mirror)
			)
		)
		(duplicate_pad_numbers_are_jumpers no)
		(fp_line
			(start 0.7874 -0.4064)
			(end -0.7874 -0.4064)
			(stroke
				(width 0.1524)
				(type default)
			)
			(layer "B.SilkS")
		)
		(fp_line
			(start -0.7874 -0.4064)
			(end -0.7874 0.4064)
			(stroke
				(width 0.1524)
				(type default)
			)
			(layer "B.SilkS")
		)
		(fp_line
			(start 0.7874 0.4064)
			(end 0.7874 -0.4064)
			(stroke
				(width 0.1524)
				(type default)
			)
			(layer "B.SilkS")
		)
		(fp_line
			(start -0.7874 0.4064)
			(end 0.7874 0.4064)
			(stroke
				(width 0.1524)
				(type default)
			)
			(layer "B.SilkS")
		)
		(fp_line
			(start 0.67945 -0.305054)
			(end 0.12065 -0.305054)
			(stroke
				(width 0.1)
				(type default)
			)
			(layer "B.Fab")
		)
		(fp_line
			(start 0.12065 -0.305054)
			(end 0.12065 -0.2794)
			(stroke
				(width 0.1)
				(type default)
			)
			(layer "B.Fab")
		)
		(fp_line
			(start -0.12065 -0.3048)
			(end -0.67945 -0.3048)
			(stroke
				(width 0.1)
				(type default)
			)
			(layer "B.Fab")
		)
		(fp_line
			(start -0.67945 -0.3048)
			(end -0.67945 0.3048)
			(stroke
				(width 0.1)
				(type default)
			)
			(layer "B.Fab")
		)
		(fp_line
			(start 0.12065 -0.2794)
			(end -0.12065 -0.2794)
			(stroke
				(width 0.1)
				(type default)
			)
			(layer "B.Fab")
		)
		(fp_line
			(start -0.12065 -0.2794)
			(end -0.12065 -0.3048)
			(stroke
				(width 0.1)
				(type default)
			)
			(layer "B.Fab")
		)
		(fp_line
			(start 0.12065 0.2794)
			(end 0.12065 0.3048)
			(stroke
				(width 0.1)
				(type default)
			)
			(layer "B.Fab")
		)
		(fp_line
			(start -0.120396 0.2794)
			(end 0.12065 0.2794)
			(stroke
				(width 0.1)
				(type default)
			)
			(layer "B.Fab")
		)
		(fp_line
			(start 0.67945 0.3048)
			(end 0.67945 -0.305054)
			(stroke
				(width 0.1)
				(type default)
			)
			(layer "B.Fab")
		)
		(fp_line
			(start 0.12065 0.3048)
			(end 0.67945 0.3048)
			(stroke
				(width 0.1)
				(type default)
			)
			(layer "B.Fab")
		)
		(fp_line
			(start -0.120396 0.3048)
			(end -0.120396 0.2794)
			(stroke
				(width 0.1)
				(type default)
			)
			(layer "B.Fab")
		)
		(fp_line
			(start -0.67945 0.3048)
			(end -0.120396 0.3048)
			(stroke
				(width 0.1)
				(type default)
			)
			(layer "B.Fab")
		)
		(pad "1" smd circle
			(at 0.40005 0 270)
			(size 0 0)
			(layers "B.Cu" "B.Mask" "B.Paste")
			(net "P3V3_OCP_V3_2")
		)
		(pad "2" smd circle
			(at -0.40005 0 270)
			(size 0 0)
			(layers "B.Cu" "B.Mask" "B.Paste")
			(net "GND")
		)
	)
	(footprint ""
		(layer "B.Cu")
		(at 124.704602 -324.978776 -90)
		(property "Reference" "PC574_P1_1"
			(at 0 0 90)
			(layer "B.SilkS")
			(hide yes)
			(effects
				(font
					(size 1.27 1.27)
				)
				(justify mirror)
			)
		)
		(property "Value" ""
			(at 0 0 90)
			(layer "B.Fab")
			(effects
				(font
					(size 1.27 1.27)
				)
				(justify mirror)
			)
		)
		(duplicate_pad_numbers_are_jumpers no)
		(fp_line
			(start -0.7874 0.4064)
			(end 0.7874 0.4064)
			(stroke
				(width 0.1524)
				(type default)
			)
			(layer "B.SilkS")
		)
		(fp_line
			(start 0.7874 0.4064)
			(end 0.7874 -0.4064)
			(stroke
				(width 0.1524)
				(type default)
			)
			(layer "B.SilkS")
		)
		(fp_line
			(start -0.7874 -0.4064)
			(end -0.7874 0.4064)
			(stroke
				(width 0.1524)
				(type default)
			)
			(layer "B.SilkS")
		)
		(fp_line
			(start 0.7874 -0.4064)
			(end -0.7874 -0.4064)
			(stroke
				(width 0.1524)
				(type default)
			)
			(layer "B.SilkS")
		)
		(fp_line
			(start -0.67945 0.3048)
			(end -0.120396 0.3048)
			(stroke
				(width 0.1)
				(type default)
			)
			(layer "B.Fab")
		)
		(fp_line
			(start -0.120396 0.3048)
			(end -0.120396 0.2794)
			(stroke
				(width 0.1)
				(type default)
			)
			(layer "B.Fab")
		)
		(fp_line
			(start 0.12065 0.3048)
			(end 0.67945 0.3048)
			(stroke
				(width 0.1)
				(type default)
			)
			(layer "B.Fab")
		)
		(fp_line
			(start 0.67945 0.3048)
			(end 0.67945 -0.305054)
			(stroke
				(width 0.1)
				(type default)
			)
			(layer "B.Fab")
		)
		(fp_line
			(start -0.120396 0.2794)
			(end 0.12065 0.2794)
			(stroke
				(width 0.1)
				(type default)
			)
			(layer "B.Fab")
		)
		(fp_line
			(start 0.12065 0.2794)
			(end 0.12065 0.3048)
			(stroke
				(width 0.1)
				(type default)
			)
			(layer "B.Fab")
		)
		(fp_line
			(start -0.12065 -0.2794)
			(end -0.12065 -0.3048)
			(stroke
				(width 0.1)
				(type default)
			)
			(layer "B.Fab")
		)
		(fp_line
			(start 0.12065 -0.2794)
			(end -0.12065 -0.2794)
			(stroke
				(width 0.1)
				(type default)
			)
			(layer "B.Fab")
		)
		(fp_line
			(start -0.67945 -0.3048)
			(end -0.67945 0.3048)
			(stroke
				(width 0.1)
				(type default)
			)
			(layer "B.Fab")
		)
		(fp_line
			(start -0.12065 -0.3048)
			(end -0.67945 -0.3048)
			(stroke
				(width 0.1)
				(type default)
			)
			(layer "B.Fab")
		)
		(fp_line
			(start 0.12065 -0.305054)
			(end 0.12065 -0.2794)
			(stroke
				(width 0.1)
				(type default)
			)
			(layer "B.Fab")
		)
		(fp_line
			(start 0.67945 -0.305054)
			(end 0.12065 -0.305054)
			(stroke
				(width 0.1)
				(type default)
			)
			(layer "B.Fab")
		)
		(pad "1" smd circle
			(at 0.40005 0 90)
			(size 0 0)
			(layers "B.Cu" "B.Mask" "B.Paste")
			(net "PVCCIN_CPU1")
		)
		(pad "2" smd circle
			(at -0.40005 0 90)
			(size 0 0)
			(layers "B.Cu" "B.Mask" "B.Paste")
			(net "GND")
		)
	)
	(footprint ""
		(layer "B.Cu")
		(at 339.298534 2.923794 180)
		(property "Reference" "J115"
			(at 4.172204 -1.521206 270)
			(unlocked yes)
			(layer "B.SilkS")
			(effects
				(font
					(size 0.7874 0.5842)
					(thickness 0.1524)
				)
				(justify left mirror)
			)
		)
		(property "Value" ""
			(at 0 0 0)
			(layer "B.Fab")
			(effects
				(font
					(size 1.27 1.27)
				)
				(justify mirror)
			)
		)
		(duplicate_pad_numbers_are_jumpers no)
		(fp_line
			(start 1.2192 2.1082)
			(end 1.2192 -2.1082)
			(stroke
				(width 0.1524)
				(type default)
			)
			(layer "B.SilkS")
		)
		(fp_line
			(start 1.2192 -2.1082)
			(end -1.2192 -2.1082)
			(stroke
				(width 0.1524)
				(type default)
			)
			(layer "B.SilkS")
		)
		(fp_line
			(start -1.2192 2.1082)
			(end 1.2192 2.1082)
			(stroke
				(width 0.1524)
				(type default)
			)
			(layer "B.SilkS")
		)
		(fp_line
			(start -1.2192 -2.1082)
			(end -1.2192 2.1082)
			(stroke
				(width 0.1524)
				(type default)
			)
			(layer "B.SilkS")
		)
		(pad "" np_thru_hole circle
			(at -3.4671 -1.27 90)
			(size 1.0414 1.0414)
			(drill 1.0414)
			(layers "*.Cu" "*.Mask")
			(clearance 0.381)
			(thermal_gap 0.381)
		)
		(pad "" np_thru_hole circle
			(at -3.4671 1.27 90)
			(size 1.0414 1.0414)
			(drill 1.0414)
			(layers "*.Cu" "*.Mask")
			(clearance 0.381)
			(thermal_gap 0.381)
		)
		(pad "" np_thru_hole circle
			(at 2.8829 -1.27 90)
			(size 1.0414 1.0414)
			(drill 1.0414)
			(layers "*.Cu" "*.Mask")
			(clearance 0.381)
			(thermal_gap 0.381)
		)
		(pad "" np_thru_hole circle
			(at 2.8829 1.27 90)
			(size 1.0414 1.0414)
			(drill 1.0414)
			(layers "*.Cu" "*.Mask")
			(clearance 0.381)
			(thermal_gap 0.381)
		)
		(pad "1" smd rect
			(at -0.8255 -0.249936 90)
			(size 0.3048 0.508)
			(layers "B.Cu" "B.Mask" "B.Paste")
			(net "DELTA_L_85_5INCH_IN6_DP")
		)
		(pad "2" smd rect
			(at -0.8255 0.249936 90)
			(size 0.3048 0.508)
			(layers "B.Cu" "B.Mask" "B.Paste")
			(net "DELTA_L_85_5INCH_IN6_DN")
		)
		(pad "3" smd circle
			(at 0 0)
			(size 0 0)
			(layers "B.Cu" "B.Mask" "B.Paste")
			(net "DELTA_L_GND_1")
		)
		(zone
			(layers "F.Cu" "B.Cu" "In1.Cu" "In2.Cu" "In3.Cu" "In4.Cu" "In5.Cu" "In6.Cu"
				"In7.Cu" "In8.Cu" "In9.Cu" "In10.Cu" "In11.Cu" "In12.Cu" "In13.Cu" "In14.Cu"
				"In15.Cu" "In16.Cu"
			)
			(hatch none 0.5)
			(connect_pads
				(clearance 0)
			)
			(min_thickness 0.25)
			(keepout
				(tracks not_allowed)
				(vias allowed)
				(pads allowed)
				(copperpour not_allowed)
				(footprints allowed)
			)
			(placement
				(enabled no)
				(sheetname "")
			)
			(fill
				(thermal_gap 0.5)
				(thermal_bridge_width 0.5)
				(island_removal_mode 0)
			)
			(polygon
				(pts
					(arc
						(start 337.342734 1.653794)
						(mid 335.488534 1.653794)
						(end 337.342734 1.653794)
					)
				)
			)
		)
		(zone
			(layers "F.Cu" "B.Cu" "In1.Cu" "In2.Cu" "In3.Cu" "In4.Cu" "In5.Cu" "In6.Cu"
				"In7.Cu" "In8.Cu" "In9.Cu" "In10.Cu" "In11.Cu" "In12.Cu" "In13.Cu" "In14.Cu"
				"In15.Cu" "In16.Cu"
			)
			(hatch none 0.5)
			(connect_pads
				(clearance 0)
			)
			(min_thickness 0.25)
			(keepout
				(tracks not_allowed)
				(vias allowed)
				(pads allowed)
				(copperpour not_allowed)
				(footprints allowed)
			)
			(placement
				(enabled no)
				(sheetname "")
			)
			(fill
				(thermal_gap 0.5)
				(thermal_bridge_width 0.5)
				(island_removal_mode 0)
			)
			(polygon
				(pts
					(arc
						(start 337.342734 4.193794)
						(mid 335.488534 4.193794)
						(end 337.342734 4.193794)
					)
				)
			)
		)
		(zone
			(layers "F.Cu" "B.Cu" "In1.Cu" "In2.Cu" "In3.Cu" "In4.Cu" "In5.Cu" "In6.Cu"
				"In7.Cu" "In8.Cu" "In9.Cu" "In10.Cu" "In11.Cu" "In12.Cu" "In13.Cu" "In14.Cu"
				"In15.Cu" "In16.Cu"
			)
			(hatch none 0.5)
			(connect_pads
				(clearance 0)
			)
			(min_thickness 0.25)
			(keepout
				(tracks not_allowed)
				(vias allowed)
				(pads allowed)
				(copperpour not_allowed)
				(footprints allowed)
			)
			(placement
				(enabled no)
				(sheetname "")
			)
			(fill
				(thermal_gap 0.5)
				(thermal_bridge_width 0.5)
				(island_removal_mode 0)
			)
			(polygon
				(pts
					(arc
						(start 343.692734 1.653794)
						(mid 341.838534 1.653794)
						(end 343.692734 1.653794)
					)
				)
			)
		)
		(zone
			(layers "F.Cu" "B.Cu" "In1.Cu" "In2.Cu" "In3.Cu" "In4.Cu" "In5.Cu" "In6.Cu"
				"In7.Cu" "In8.Cu" "In9.Cu" "In10.Cu" "In11.Cu" "In12.Cu" "In13.Cu" "In14.Cu"
				"In15.Cu" "In16.Cu"
			)
			(hatch none 0.5)
			(connect_pads
				(clearance 0)
			)
			(min_thickness 0.25)
			(keepout
				(tracks not_allowed)
				(vias allowed)
				(pads allowed)
				(copperpour not_allowed)
				(footprints allowed)
			)
			(placement
				(enabled no)
				(sheetname "")
			)
			(fill
				(thermal_gap 0.5)
				(thermal_bridge_width 0.5)
				(island_removal_mode 0)
			)
			(polygon
				(pts
					(arc
						(start 343.692734 4.193794)
						(mid 341.838534 4.193794)
						(end 343.692734 4.193794)
					)
				)
			)
		)
		(zone
			(layer "B.Cu")
			(hatch none 0.5)
			(connect_pads
				(clearance 0)
			)
			(min_thickness 0.25)
			(keepout
				(tracks not_allowed)
				(vias allowed)
				(pads allowed)
				(copperpour not_allowed)
				(footprints allowed)
			)
			(placement
				(enabled no)
				(sheetname "")
			)
			(fill
				(thermal_gap 0.5)
				(thermal_bridge_width 0.5)
				(island_removal_mode 0)
			)
			(polygon
				(pts
					(xy 340.416134 3.472434) (xy 340.416134 3.37693) (xy 339.819234 3.37693) (xy 339.819234 2.97053)
					(xy 340.416134 2.97053) (xy 340.416134 2.877058) (xy 339.819234 2.877058) (xy 339.819234 2.470658)
					(xy 340.416134 2.470658) (xy 340.416134 2.375154) (xy 339.717634 2.375154) (xy 339.717634 3.472434)
				)
			)
		)
	)
	(footprint ""
		(layer "B.Cu")
		(at 269.684246 -193.503296 -90)
		(property "Reference" "R837"
			(at 0 0 90)
			(layer "B.SilkS")
			(hide yes)
			(effects
				(font
					(size 1.27 1.27)
				)
				(justify mirror)
			)
		)
		(property "Value" ""
			(at 0 0 90)
			(layer "B.Fab")
			(effects
				(font
					(size 1.27 1.27)
				)
				(justify mirror)
			)
		)
		(duplicate_pad_numbers_are_jumpers no)
		(fp_line
			(start -0.7874 0.4064)
			(end 0.7874 0.4064)
			(stroke
				(width 0.1524)
				(type default)
			)
			(layer "B.SilkS")
		)
		(fp_line
			(start 0.7874 0.4064)
			(end 0.7874 -0.4064)
			(stroke
				(width 0.1524)
				(type default)
			)
			(layer "B.SilkS")
		)
		(fp_line
			(start -0.7874 -0.4064)
			(end -0.7874 0.4064)
			(stroke
				(width 0.1524)
				(type default)
			)
			(layer "B.SilkS")
		)
		(fp_line
			(start 0.7874 -0.4064)
			(end -0.7874 -0.4064)
			(stroke
				(width 0.1524)
				(type default)
			)
			(layer "B.SilkS")
		)
		(fp_line
			(start -0.67945 0.3048)
			(end -0.120396 0.3048)
			(stroke
				(width 0.1)
				(type default)
			)
			(layer "B.Fab")
		)
		(fp_line
			(start -0.120396 0.3048)
			(end -0.120396 0.2794)
			(stroke
				(width 0.1)
				(type default)
			)
			(layer "B.Fab")
		)
		(fp_line
			(start 0.12065 0.3048)
			(end 0.67945 0.3048)
			(stroke
				(width 0.1)
				(type default)
			)
			(layer "B.Fab")
		)
		(fp_line
			(start 0.67945 0.3048)
			(end 0.67945 -0.305054)
			(stroke
				(width 0.1)
				(type default)
			)
			(layer "B.Fab")
		)
		(fp_line
			(start -0.120396 0.2794)
			(end 0.12065 0.2794)
			(stroke
				(width 0.1)
				(type default)
			)
			(layer "B.Fab")
		)
		(fp_line
			(start 0.12065 0.2794)
			(end 0.12065 0.3048)
			(stroke
				(width 0.1)
				(type default)
			)
			(layer "B.Fab")
		)
		(fp_line
			(start -0.12065 -0.2794)
			(end -0.12065 -0.3048)
			(stroke
				(width 0.1)
				(type default)
			)
			(layer "B.Fab")
		)
		(fp_line
			(start 0.12065 -0.2794)
			(end -0.12065 -0.2794)
			(stroke
				(width 0.1)
				(type default)
			)
			(layer "B.Fab")
		)
		(fp_line
			(start -0.67945 -0.3048)
			(end -0.67945 0.3048)
			(stroke
				(width 0.1)
				(type default)
			)
			(layer "B.Fab")
		)
		(fp_line
			(start -0.12065 -0.3048)
			(end -0.67945 -0.3048)
			(stroke
				(width 0.1)
				(type default)
			)
			(layer "B.Fab")
		)
		(fp_line
			(start 0.12065 -0.305054)
			(end 0.12065 -0.2794)
			(stroke
				(width 0.1)
				(type default)
			)
			(layer "B.Fab")
		)
		(fp_line
			(start 0.67945 -0.305054)
			(end 0.12065 -0.305054)
			(stroke
				(width 0.1)
				(type default)
			)
			(layer "B.Fab")
		)
		(pad "1" smd circle
			(at 0.40005 0 90)
			(size 0 0)
			(layers "B.Cu" "B.Mask" "B.Paste")
			(net "RST_PLD_CPU0_DRAM_CD_N")
		)
		(pad "2" smd circle
			(at -0.40005 0 90)
			(size 0 0)
			(layers "B.Cu" "B.Mask" "B.Paste")
			(net "RST_M_CD_CPU0_FPGA_N")
		)
	)
	(footprint ""
		(layer "B.Cu")
		(at 434.77688 -124.932948 90)
		(property "Reference" "PR4232"
			(at 0 0 90)
			(layer "B.SilkS")
			(hide yes)
			(effects
				(font
					(size 1.27 1.27)
				)
				(justify mirror)
			)
		)
		(property "Value" ""
			(at 0 0 90)
			(layer "B.Fab")
			(effects
				(font
					(size 1.27 1.27)
				)
				(justify mirror)
			)
		)
		(duplicate_pad_numbers_are_jumpers no)
		(fp_line
			(start 0.7874 -0.4064)
			(end -0.7874 -0.4064)
			(stroke
				(width 0.1524)
				(type default)
			)
			(layer "B.SilkS")
		)
		(fp_line
			(start -0.7874 -0.4064)
			(end -0.7874 0.4064)
			(stroke
				(width 0.1524)
				(type default)
			)
			(layer "B.SilkS")
		)
		(fp_line
			(start 0.7874 0.4064)
			(end 0.7874 -0.4064)
			(stroke
				(width 0.1524)
				(type default)
			)
			(layer "B.SilkS")
		)
		(fp_line
			(start -0.7874 0.4064)
			(end 0.7874 0.4064)
			(stroke
				(width 0.1524)
				(type default)
			)
			(layer "B.SilkS")
		)
		(fp_line
			(start 0.67945 -0.305054)
			(end 0.12065 -0.305054)
			(stroke
				(width 0.1)
				(type default)
			)
			(layer "B.Fab")
		)
		(fp_line
			(start 0.12065 -0.305054)
			(end 0.12065 -0.2794)
			(stroke
				(width 0.1)
				(type default)
			)
			(layer "B.Fab")
		)
		(fp_line
			(start -0.12065 -0.3048)
			(end -0.67945 -0.3048)
			(stroke
				(width 0.1)
				(type default)
			)
			(layer "B.Fab")
		)
		(fp_line
			(start -0.67945 -0.3048)
			(end -0.67945 0.3048)
			(stroke
				(width 0.1)
				(type default)
			)
			(layer "B.Fab")
		)
		(fp_line
			(start 0.12065 -0.2794)
			(end -0.12065 -0.2794)
			(stroke
				(width 0.1)
				(type default)
			)
			(layer "B.Fab")
		)
		(fp_line
			(start -0.12065 -0.2794)
			(end -0.12065 -0.3048)
			(stroke
				(width 0.1)
				(type default)
			)
			(layer "B.Fab")
		)
		(fp_line
			(start 0.12065 0.2794)
			(end 0.12065 0.3048)
			(stroke
				(width 0.1)
				(type default)
			)
			(layer "B.Fab")
		)
		(fp_line
			(start -0.120396 0.2794)
			(end 0.12065 0.2794)
			(stroke
				(width 0.1)
				(type default)
			)
			(layer "B.Fab")
		)
		(fp_line
			(start 0.67945 0.3048)
			(end 0.67945 -0.305054)
			(stroke
				(width 0.1)
				(type default)
			)
			(layer "B.Fab")
		)
		(fp_line
			(start 0.12065 0.3048)
			(end 0.67945 0.3048)
			(stroke
				(width 0.1)
				(type default)
			)
			(layer "B.Fab")
		)
		(fp_line
			(start -0.120396 0.3048)
			(end -0.120396 0.2794)
			(stroke
				(width 0.1)
				(type default)
			)
			(layer "B.Fab")
		)
		(fp_line
			(start -0.67945 0.3048)
			(end -0.120396 0.3048)
			(stroke
				(width 0.1)
				(type default)
			)
			(layer "B.Fab")
		)
		(pad "1" smd circle
			(at 0.40005 0 270)
			(size 0 0)
			(layers "B.Cu" "B.Mask" "B.Paste")
			(net "NC_PVCCD_HV_CPU0_ACSP4")
		)
		(pad "2" smd circle
			(at -0.40005 0 270)
			(size 0 0)
			(layers "B.Cu" "B.Mask" "B.Paste")
			(net "GND")
		)
	)
)
